(kicad_pcb
	(version 20260206)
	(generator "pcbnew")
	(generator_version "10.0")
	(general
		(thickness 1.6)
		(legacy_teardrops no)
	)
	(paper "A4")
	(title_block
		(title "12092022_DA0F0TMDCD0_F0T_Management_Board_D_brd_V3_OCP.brd")
		(comment 1 "Grand Teton / footprints 91-96 of 1440")
	)
	(layers
		(0 "F.Cu" signal "TOP")
		(4 "In1.Cu" signal "GND")
		(6 "In2.Cu" signal "IN1")
		(8 "In3.Cu" signal "GND1")
		(10 "In4.Cu" signal "IN2")
		(12 "In5.Cu" signal "VCC")
		(14 "In6.Cu" signal "VCC1")
		(16 "In7.Cu" signal "IN3")
		(18 "In8.Cu" signal "GND2")
		(20 "In9.Cu" signal "IN4")
		(22 "In10.Cu" signal "GND3")
		(2 "B.Cu" signal "BOTTOM")
		(9 "F.Adhes" user "F.Adhesive")
		(11 "B.Adhes" user "B.Adhesive")
		(13 "F.Paste" user "Package Geometry/Pastemask Top")
		(15 "B.Paste" user "Package Geometry/Pastemask Bottom")
		(5 "F.SilkS" user "Ref Des/Silkscreen Top")
		(7 "B.SilkS" user "Ref Des/Silkscreen Bottom")
		(1 "F.Mask" user "Board Geometry/Soldermask Top")
		(3 "B.Mask" user "Board Geometry/Soldermask Bottom")
		(17 "Dwgs.User" user "User.Drawings")
		(19 "Cmts.User" user "User.Comments")
		(21 "Eco1.User" user "User.Eco1")
		(23 "Eco2.User" user "User.Eco2")
		(25 "Edge.Cuts" user "Board Geometry/Outline")
		(27 "Margin" user)
		(31 "F.CrtYd" user "Package Geometry/Place Bound Top")
		(29 "B.CrtYd" user "Package Geometry/Place Bound Bottom")
		(35 "F.Fab" user "Ref Des/Assembly Top")
		(33 "B.Fab" user "Ref Des/Assembly Bottom")
	)
	(footprint ""
		(layer "F.Cu")
		(at 57.5691 -95.96374 90)
		(property "Reference" "R505"
			(at 0 0 90)
			(layer "F.SilkS")
			(hide yes)
			(effects
				(font
					(size 1.27 1.27)
				)
			)
		)
		(property "Value" ""
			(at 0 0 90)
			(layer "F.Fab")
			(effects
				(font
					(size 1.27 1.27)
				)
			)
		)
		(duplicate_pad_numbers_are_jumpers no)
		(fp_line
			(start 0.7874 -0.4064)
			(end 0.7874 0.4064)
			(stroke
				(width 0.1524)
				(type default)
			)
			(layer "F.SilkS")
		)
		(fp_line
			(start -0.7874 -0.4064)
			(end 0.7874 -0.4064)
			(stroke
				(width 0.1524)
				(type default)
			)
			(layer "F.SilkS")
		)
		(fp_line
			(start 0.7874 0.4064)
			(end -0.7874 0.4064)
			(stroke
				(width 0.1524)
				(type default)
			)
			(layer "F.SilkS")
		)
		(fp_line
			(start -0.7874 0.4064)
			(end -0.7874 -0.4064)
			(stroke
				(width 0.1524)
				(type default)
			)
			(layer "F.SilkS")
		)
		(fp_line
			(start -0.12065 -0.305054)
			(end -0.12065 -0.2794)
			(stroke
				(width 0.1)
				(type default)
			)
			(layer "F.Fab")
		)
		(fp_line
			(start -0.67945 -0.305054)
			(end -0.12065 -0.305054)
			(stroke
				(width 0.1)
				(type default)
			)
			(layer "F.Fab")
		)
		(fp_line
			(start 0.67945 -0.3048)
			(end 0.67945 0.3048)
			(stroke
				(width 0.1)
				(type default)
			)
			(layer "F.Fab")
		)
		(fp_line
			(start 0.12065 -0.3048)
			(end 0.67945 -0.3048)
			(stroke
				(width 0.1)
				(type default)
			)
			(layer "F.Fab")
		)
		(fp_line
			(start 0.12065 -0.2794)
			(end 0.12065 -0.3048)
			(stroke
				(width 0.1)
				(type default)
			)
			(layer "F.Fab")
		)
		(fp_line
			(start -0.12065 -0.2794)
			(end 0.12065 -0.2794)
			(stroke
				(width 0.1)
				(type default)
			)
			(layer "F.Fab")
		)
		(fp_line
			(start 0.120396 0.2794)
			(end -0.12065 0.2794)
			(stroke
				(width 0.1)
				(type default)
			)
			(layer "F.Fab")
		)
		(fp_line
			(start -0.12065 0.2794)
			(end -0.12065 0.3048)
			(stroke
				(width 0.1)
				(type default)
			)
			(layer "F.Fab")
		)
		(fp_line
			(start 0.67945 0.3048)
			(end 0.120396 0.3048)
			(stroke
				(width 0.1)
				(type default)
			)
			(layer "F.Fab")
		)
		(fp_line
			(start 0.120396 0.3048)
			(end 0.120396 0.2794)
			(stroke
				(width 0.1)
				(type default)
			)
			(layer "F.Fab")
		)
		(fp_line
			(start -0.12065 0.3048)
			(end -0.67945 0.3048)
			(stroke
				(width 0.1)
				(type default)
			)
			(layer "F.Fab")
		)
		(fp_line
			(start -0.67945 0.3048)
			(end -0.67945 -0.305054)
			(stroke
				(width 0.1)
				(type default)
			)
			(layer "F.Fab")
		)
		(pad "1" smd circle
			(at -0.40005 0 90)
			(size 0 0)
			(layers "F.Cu" "F.Mask" "F.Paste")
			(net "IRQ_PCH_TPM_SPI_N")
		)
		(pad "2" smd circle
			(at 0.40005 0 90)
			(size 0 0)
			(layers "F.Cu" "F.Mask" "F.Paste")
			(net "IRQ_PCH_TPM_SPI_R_N")
		)
	)
	(footprint ""
		(layer "F.Cu")
		(at 40.005 -58.547 90)
		(property "Reference" "C154"
			(at 0 0 90)
			(layer "F.SilkS")
			(hide yes)
			(effects
				(font
					(size 1.27 1.27)
				)
			)
		)
		(property "Value" ""
			(at 0 0 90)
			(layer "F.Fab")
			(effects
				(font
					(size 1.27 1.27)
				)
			)
		)
		(duplicate_pad_numbers_are_jumpers no)
		(fp_line
			(start 0.7874 -0.4064)
			(end 0.7874 0.4064)
			(stroke
				(width 0.1524)
				(type default)
			)
			(layer "F.SilkS")
		)
		(fp_line
			(start -0.7874 -0.4064)
			(end 0.7874 -0.4064)
			(stroke
				(width 0.1524)
				(type default)
			)
			(layer "F.SilkS")
		)
		(fp_line
			(start 0.7874 0.4064)
			(end -0.7874 0.4064)
			(stroke
				(width 0.1524)
				(type default)
			)
			(layer "F.SilkS")
		)
		(fp_line
			(start -0.7874 0.4064)
			(end -0.7874 -0.4064)
			(stroke
				(width 0.1524)
				(type default)
			)
			(layer "F.SilkS")
		)
		(fp_line
			(start -0.12065 -0.305054)
			(end -0.12065 -0.2794)
			(stroke
				(width 0.1)
				(type default)
			)
			(layer "F.Fab")
		)
		(fp_line
			(start -0.67945 -0.305054)
			(end -0.12065 -0.305054)
			(stroke
				(width 0.1)
				(type default)
			)
			(layer "F.Fab")
		)
		(fp_line
			(start 0.67945 -0.3048)
			(end 0.67945 0.3048)
			(stroke
				(width 0.1)
				(type default)
			)
			(layer "F.Fab")
		)
		(fp_line
			(start 0.12065 -0.3048)
			(end 0.67945 -0.3048)
			(stroke
				(width 0.1)
				(type default)
			)
			(layer "F.Fab")
		)
		(fp_line
			(start 0.12065 -0.2794)
			(end 0.12065 -0.3048)
			(stroke
				(width 0.1)
				(type default)
			)
			(layer "F.Fab")
		)
		(fp_line
			(start -0.12065 -0.2794)
			(end 0.12065 -0.2794)
			(stroke
				(width 0.1)
				(type default)
			)
			(layer "F.Fab")
		)
		(fp_line
			(start 0.120396 0.2794)
			(end -0.12065 0.2794)
			(stroke
				(width 0.1)
				(type default)
			)
			(layer "F.Fab")
		)
		(fp_line
			(start -0.12065 0.2794)
			(end -0.12065 0.3048)
			(stroke
				(width 0.1)
				(type default)
			)
			(layer "F.Fab")
		)
		(fp_line
			(start 0.67945 0.3048)
			(end 0.120396 0.3048)
			(stroke
				(width 0.1)
				(type default)
			)
			(layer "F.Fab")
		)
		(fp_line
			(start 0.120396 0.3048)
			(end 0.120396 0.2794)
			(stroke
				(width 0.1)
				(type default)
			)
			(layer "F.Fab")
		)
		(fp_line
			(start -0.12065 0.3048)
			(end -0.67945 0.3048)
			(stroke
				(width 0.1)
				(type default)
			)
			(layer "F.Fab")
		)
		(fp_line
			(start -0.67945 0.3048)
			(end -0.67945 -0.305054)
			(stroke
				(width 0.1)
				(type default)
			)
			(layer "F.Fab")
		)
		(pad "1" smd circle
			(at -0.40005 0 90)
			(size 0 0)
			(layers "F.Cu" "F.Mask" "F.Paste")
			(net "PWRGD_P1V8_AUX_R")
		)
		(pad "2" smd circle
			(at 0.40005 0 90)
			(size 0 0)
			(layers "F.Cu" "F.Mask" "F.Paste")
			(net "GND")
		)
	)
	(footprint ""
		(layer "F.Cu")
		(at 36.07054 -45.50664 180)
		(property "Reference" "R405"
			(at 0 0 180)
			(layer "F.SilkS")
			(hide yes)
			(effects
				(font
					(size 1.27 1.27)
				)
			)
		)
		(property "Value" ""
			(at 0 0 180)
			(layer "F.Fab")
			(effects
				(font
					(size 1.27 1.27)
				)
			)
		)
		(duplicate_pad_numbers_are_jumpers no)
		(fp_line
			(start 0.7874 0.4064)
			(end -0.7874 0.4064)
			(stroke
				(width 0.1524)
				(type default)
			)
			(layer "F.SilkS")
		)
		(fp_line
			(start 0.7874 -0.4064)
			(end 0.7874 0.4064)
			(stroke
				(width 0.1524)
				(type default)
			)
			(layer "F.SilkS")
		)
		(fp_line
			(start -0.7874 0.4064)
			(end -0.7874 -0.4064)
			(stroke
				(width 0.1524)
				(type default)
			)
			(layer "F.SilkS")
		)
		(fp_line
			(start -0.7874 -0.4064)
			(end 0.7874 -0.4064)
			(stroke
				(width 0.1524)
				(type default)
			)
			(layer "F.SilkS")
		)
		(fp_line
			(start 0.67945 0.3048)
			(end 0.120396 0.3048)
			(stroke
				(width 0.1)
				(type default)
			)
			(layer "F.Fab")
		)
		(fp_line
			(start 0.67945 -0.3048)
			(end 0.67945 0.3048)
			(stroke
				(width 0.1)
				(type default)
			)
			(layer "F.Fab")
		)
		(fp_line
			(start 0.12065 -0.2794)
			(end 0.12065 -0.3048)
			(stroke
				(width 0.1)
				(type default)
			)
			(layer "F.Fab")
		)
		(fp_line
			(start 0.12065 -0.3048)
			(end 0.67945 -0.3048)
			(stroke
				(width 0.1)
				(type default)
			)
			(layer "F.Fab")
		)
		(fp_line
			(start 0.120396 0.3048)
			(end 0.120396 0.2794)
			(stroke
				(width 0.1)
				(type default)
			)
			(layer "F.Fab")
		)
		(fp_line
			(start 0.120396 0.2794)
			(end -0.12065 0.2794)
			(stroke
				(width 0.1)
				(type default)
			)
			(layer "F.Fab")
		)
		(fp_line
			(start -0.12065 0.3048)
			(end -0.67945 0.3048)
			(stroke
				(width 0.1)
				(type default)
			)
			(layer "F.Fab")
		)
		(fp_line
			(start -0.12065 0.2794)
			(end -0.12065 0.3048)
			(stroke
				(width 0.1)
				(type default)
			)
			(layer "F.Fab")
		)
		(fp_line
			(start -0.12065 -0.2794)
			(end 0.12065 -0.2794)
			(stroke
				(width 0.1)
				(type default)
			)
			(layer "F.Fab")
		)
		(fp_line
			(start -0.12065 -0.305054)
			(end -0.12065 -0.2794)
			(stroke
				(width 0.1)
				(type default)
			)
			(layer "F.Fab")
		)
		(fp_line
			(start -0.67945 0.3048)
			(end -0.67945 -0.305054)
			(stroke
				(width 0.1)
				(type default)
			)
			(layer "F.Fab")
		)
		(fp_line
			(start -0.67945 -0.305054)
			(end -0.12065 -0.305054)
			(stroke
				(width 0.1)
				(type default)
			)
			(layer "F.Fab")
		)
		(pad "1" smd circle
			(at -0.40005 0 180)
			(size 0 0)
			(layers "F.Cu" "F.Mask" "F.Paste")
			(net "PD_BIOS_MUX_EN_R_N")
		)
		(pad "2" smd circle
			(at 0.40005 0 180)
			(size 0 0)
			(layers "F.Cu" "F.Mask" "F.Paste")
			(net "PD_BIOS_MUX_EN_N")
		)
	)
	(footprint ""
		(layer "F.Cu")
		(at 68.189094 -96.79305 180)
		(property "Reference" "R499"
			(at 0 0 180)
			(layer "F.SilkS")
			(hide yes)
			(effects
				(font
					(size 1.27 1.27)
				)
			)
		)
		(property "Value" ""
			(at 0 0 180)
			(layer "F.Fab")
			(effects
				(font
					(size 1.27 1.27)
				)
			)
		)
		(duplicate_pad_numbers_are_jumpers no)
		(fp_line
			(start 0.7874 0.4064)
			(end -0.7874 0.4064)
			(stroke
				(width 0.1524)
				(type default)
			)
			(layer "F.SilkS")
		)
		(fp_line
			(start 0.7874 -0.4064)
			(end 0.7874 0.4064)
			(stroke
				(width 0.1524)
				(type default)
			)
			(layer "F.SilkS")
		)
		(fp_line
			(start -0.7874 0.4064)
			(end -0.7874 -0.4064)
			(stroke
				(width 0.1524)
				(type default)
			)
			(layer "F.SilkS")
		)
		(fp_line
			(start -0.7874 -0.4064)
			(end 0.7874 -0.4064)
			(stroke
				(width 0.1524)
				(type default)
			)
			(layer "F.SilkS")
		)
		(fp_line
			(start 0.67945 0.3048)
			(end 0.120396 0.3048)
			(stroke
				(width 0.1)
				(type default)
			)
			(layer "F.Fab")
		)
		(fp_line
			(start 0.67945 -0.3048)
			(end 0.67945 0.3048)
			(stroke
				(width 0.1)
				(type default)
			)
			(layer "F.Fab")
		)
		(fp_line
			(start 0.12065 -0.2794)
			(end 0.12065 -0.3048)
			(stroke
				(width 0.1)
				(type default)
			)
			(layer "F.Fab")
		)
		(fp_line
			(start 0.12065 -0.3048)
			(end 0.67945 -0.3048)
			(stroke
				(width 0.1)
				(type default)
			)
			(layer "F.Fab")
		)
		(fp_line
			(start 0.120396 0.3048)
			(end 0.120396 0.2794)
			(stroke
				(width 0.1)
				(type default)
			)
			(layer "F.Fab")
		)
		(fp_line
			(start 0.120396 0.2794)
			(end -0.12065 0.2794)
			(stroke
				(width 0.1)
				(type default)
			)
			(layer "F.Fab")
		)
		(fp_line
			(start -0.12065 0.3048)
			(end -0.67945 0.3048)
			(stroke
				(width 0.1)
				(type default)
			)
			(layer "F.Fab")
		)
		(fp_line
			(start -0.12065 0.2794)
			(end -0.12065 0.3048)
			(stroke
				(width 0.1)
				(type default)
			)
			(layer "F.Fab")
		)
		(fp_line
			(start -0.12065 -0.2794)
			(end 0.12065 -0.2794)
			(stroke
				(width 0.1)
				(type default)
			)
			(layer "F.Fab")
		)
		(fp_line
			(start -0.12065 -0.305054)
			(end -0.12065 -0.2794)
			(stroke
				(width 0.1)
				(type default)
			)
			(layer "F.Fab")
		)
		(fp_line
			(start -0.67945 0.3048)
			(end -0.67945 -0.305054)
			(stroke
				(width 0.1)
				(type default)
			)
			(layer "F.Fab")
		)
		(fp_line
			(start -0.67945 -0.305054)
			(end -0.12065 -0.305054)
			(stroke
				(width 0.1)
				(type default)
			)
			(layer "F.Fab")
		)
		(pad "1" smd circle
			(at -0.40005 0 180)
			(size 0 0)
			(layers "F.Cu" "F.Mask" "F.Paste")
			(net "SPI_SYS_R_MISO")
		)
		(pad "2" smd circle
			(at 0.40005 0 180)
			(size 0 0)
			(layers "F.Cu" "F.Mask" "F.Paste")
			(net "SPI_SYS_R1_MISO")
		)
	)
	(footprint ""
		(layer "F.Cu")
		(at 39.9796 -40.2082)
		(property "Reference" "R122"
			(at 0 0 0)
			(layer "F.SilkS")
			(hide yes)
			(effects
				(font
					(size 1.27 1.27)
				)
			)
		)
		(property "Value" ""
			(at 0 0 0)
			(layer "F.Fab")
			(effects
				(font
					(size 1.27 1.27)
				)
			)
		)
		(duplicate_pad_numbers_are_jumpers no)
		(fp_line
			(start -0.7874 -0.4064)
			(end 0.7874 -0.4064)
			(stroke
				(width 0.1524)
				(type default)
			)
			(layer "F.SilkS")
		)
		(fp_line
			(start -0.7874 0.4064)
			(end -0.7874 -0.4064)
			(stroke
				(width 0.1524)
				(type default)
			)
			(layer "F.SilkS")
		)
		(fp_line
			(start 0.7874 -0.4064)
			(end 0.7874 0.4064)
			(stroke
				(width 0.1524)
				(type default)
			)
			(layer "F.SilkS")
		)
		(fp_line
			(start 0.7874 0.4064)
			(end -0.7874 0.4064)
			(stroke
				(width 0.1524)
				(type default)
			)
			(layer "F.SilkS")
		)
		(fp_line
			(start -0.67945 -0.305054)
			(end -0.12065 -0.305054)
			(stroke
				(width 0.1)
				(type default)
			)
			(layer "F.Fab")
		)
		(fp_line
			(start -0.67945 0.3048)
			(end -0.67945 -0.305054)
			(stroke
				(width 0.1)
				(type default)
			)
			(layer "F.Fab")
		)
		(fp_line
			(start -0.12065 -0.305054)
			(end -0.12065 -0.2794)
			(stroke
				(width 0.1)
				(type default)
			)
			(layer "F.Fab")
		)
		(fp_line
			(start -0.12065 -0.2794)
			(end 0.12065 -0.2794)
			(stroke
				(width 0.1)
				(type default)
			)
			(layer "F.Fab")
		)
		(fp_line
			(start -0.12065 0.2794)
			(end -0.12065 0.3048)
			(stroke
				(width 0.1)
				(type default)
			)
			(layer "F.Fab")
		)
		(fp_line
			(start -0.12065 0.3048)
			(end -0.67945 0.3048)
			(stroke
				(width 0.1)
				(type default)
			)
			(layer "F.Fab")
		)
		(fp_line
			(start 0.120396 0.2794)
			(end -0.12065 0.2794)
			(stroke
				(width 0.1)
				(type default)
			)
			(layer "F.Fab")
		)
		(fp_line
			(start 0.120396 0.3048)
			(end 0.120396 0.2794)
			(stroke
				(width 0.1)
				(type default)
			)
			(layer "F.Fab")
		)
		(fp_line
			(start 0.12065 -0.3048)
			(end 0.67945 -0.3048)
			(stroke
				(width 0.1)
				(type default)
			)
			(layer "F.Fab")
		)
		(fp_line
			(start 0.12065 -0.2794)
			(end 0.12065 -0.3048)
			(stroke
				(width 0.1)
				(type default)
			)
			(layer "F.Fab")
		)
		(fp_line
			(start 0.67945 -0.3048)
			(end 0.67945 0.3048)
			(stroke
				(width 0.1)
				(type default)
			)
			(layer "F.Fab")
		)
		(fp_line
			(start 0.67945 0.3048)
			(end 0.120396 0.3048)
			(stroke
				(width 0.1)
				(type default)
			)
			(layer "F.Fab")
		)
		(pad "1" smd circle
			(at -0.40005 0)
			(size 0 0)
			(layers "F.Cu" "F.Mask" "F.Paste")
			(net "FM_BIC_DEBUG_SW_N")
		)
		(pad "2" smd circle
			(at 0.40005 0)
			(size 0 0)
			(layers "F.Cu" "F.Mask" "F.Paste")
			(net "FM_BIC_DEBUG_SW_N_R")
		)
	)
	(footprint ""
		(layer "F.Cu")
		(at 12.4206 -100.1649 180)
		(property "Reference" "R318"
			(at 0 0 180)
			(layer "F.SilkS")
			(hide yes)
			(effects
				(font
					(size 1.27 1.27)
				)
			)
		)
		(property "Value" ""
			(at 0 0 180)
			(layer "F.Fab")
			(effects
				(font
					(size 1.27 1.27)
				)
			)
		)
		(duplicate_pad_numbers_are_jumpers no)
		(fp_line
			(start 0.7874 0.4064)
			(end -0.7874 0.4064)
			(stroke
				(width 0.1524)
				(type default)
			)
			(layer "F.SilkS")
		)
		(fp_line
			(start 0.7874 -0.4064)
			(end 0.7874 0.4064)
			(stroke
				(width 0.1524)
				(type default)
			)
			(layer "F.SilkS")
		)
		(fp_line
			(start -0.7874 0.4064)
			(end -0.7874 -0.4064)
			(stroke
				(width 0.1524)
				(type default)
			)
			(layer "F.SilkS")
		)
		(fp_line
			(start -0.7874 -0.4064)
			(end 0.7874 -0.4064)
			(stroke
				(width 0.1524)
				(type default)
			)
			(layer "F.SilkS")
		)
		(fp_line
			(start 0.67945 0.3048)
			(end 0.120396 0.3048)
			(stroke
				(width 0.1)
				(type default)
			)
			(layer "F.Fab")
		)
		(fp_line
			(start 0.67945 -0.3048)
			(end 0.67945 0.3048)
			(stroke
				(width 0.1)
				(type default)
			)
			(layer "F.Fab")
		)
		(fp_line
			(start 0.12065 -0.2794)
			(end 0.12065 -0.3048)
			(stroke
				(width 0.1)
				(type default)
			)
			(layer "F.Fab")
		)
		(fp_line
			(start 0.12065 -0.3048)
			(end 0.67945 -0.3048)
			(stroke
				(width 0.1)
				(type default)
			)
			(layer "F.Fab")
		)
		(fp_line
			(start 0.120396 0.3048)
			(end 0.120396 0.2794)
			(stroke
				(width 0.1)
				(type default)
			)
			(layer "F.Fab")
		)
		(fp_line
			(start 0.120396 0.2794)
			(end -0.12065 0.2794)
			(stroke
				(width 0.1)
				(type default)
			)
			(layer "F.Fab")
		)
		(fp_line
			(start -0.12065 0.3048)
			(end -0.67945 0.3048)
			(stroke
				(width 0.1)
				(type default)
			)
			(layer "F.Fab")
		)
		(fp_line
			(start -0.12065 0.2794)
			(end -0.12065 0.3048)
			(stroke
				(width 0.1)
				(type default)
			)
			(layer "F.Fab")
		)
		(fp_line
			(start -0.12065 -0.2794)
			(end 0.12065 -0.2794)
			(stroke
				(width 0.1)
				(type default)
			)
			(layer "F.Fab")
		)
		(fp_line
			(start -0.12065 -0.305054)
			(end -0.12065 -0.2794)
			(stroke
				(width 0.1)
				(type default)
			)
			(layer "F.Fab")
		)
		(fp_line
			(start -0.67945 0.3048)
			(end -0.67945 -0.305054)
			(stroke
				(width 0.1)
				(type default)
			)
			(layer "F.Fab")
		)
		(fp_line
			(start -0.67945 -0.305054)
			(end -0.12065 -0.305054)
			(stroke
				(width 0.1)
				(type default)
			)
			(layer "F.Fab")
		)
		(pad "1" smd circle
			(at -0.40005 0 180)
			(size 0 0)
			(layers "F.Cu" "F.Mask" "F.Paste")
			(net "PWRGD_P3V3_AUX_R1")
		)
		(pad "2" smd circle
			(at 0.40005 0 180)
			(size 0 0)
			(layers "F.Cu" "F.Mask" "F.Paste")
			(net "PWRGD_P3V3_AUX")
		)
	)
)
